(kicad_pcb
	(version 20260206)
	(generator "pcbnew")
	(generator_version "10.0")
	(general
		(thickness 1.6)
		(legacy_teardrops no)
	)
	(paper "A4")
	(title_block
		(title "Bryce Canyon_IOM_IOC_16318-2_OCP.brd")
		(comment 1 "Bryce Canyon / footprints 215-222 of 1605")
	)
	(layers
		(0 "F.Cu" signal "TOP")
		(4 "In1.Cu" signal "L2GND")
		(6 "In2.Cu" signal "L3")
		(8 "In3.Cu" signal "L4VCC")
		(10 "In4.Cu" signal "L5VCC")
		(12 "In5.Cu" signal "L6")
		(14 "In6.Cu" signal "L7GND")
		(2 "B.Cu" signal "BOTTOM")
		(9 "F.Adhes" user "F.Adhesive")
		(11 "B.Adhes" user "B.Adhesive")
		(13 "F.Paste" user "Package Geometry/Pastemask Top")
		(15 "B.Paste" user "Package Geometry/Pastemask Bottom")
		(5 "F.SilkS" user "Ref Des/Silkscreen Top")
		(7 "B.SilkS" user "Ref Des/Silkscreen Bottom")
		(1 "F.Mask" user "Board Geometry/Soldermask Top")
		(3 "B.Mask" user "Board Geometry/Soldermask Bottom")
		(17 "Dwgs.User" user "User.Drawings")
		(19 "Cmts.User" user "User.Comments")
		(21 "Eco1.User" user "User.Eco1")
		(23 "Eco2.User" user "User.Eco2")
		(25 "Edge.Cuts" user "Board Geometry/Outline")
		(27 "Margin" user)
		(31 "F.CrtYd" user "Package Geometry/Place Bound Top")
		(29 "B.CrtYd" user "Package Geometry/Place Bound Bottom")
		(35 "F.Fab" user "Ref Des/Assembly Top")
		(33 "B.Fab" user "Ref Des/Assembly Bottom")
	)
	(footprint ""
		(layer "F.Cu")
		(at 177.1396 -39.497)
		(property "Reference" "TP171"
			(at 0 0 0)
			(layer "F.SilkS")
			(hide yes)
			(effects
				(font
					(size 1.27 1.27)
				)
			)
		)
		(property "Value" "TPAD28-2-GP"
			(at -0.0127 -1.6637 0)
			(unlocked yes)
			(layer "F.Fab")
			(hide yes)
			(effects
				(font
					(size 1.016 1.016)
					(thickness 0.1524)
				)
			)
		)
		(property "Device Type" "TPAD28"
			(at -0.0127 -3.1877 0)
			(unlocked yes)
			(layer "F.Fab")
			(hide yes)
			(effects
				(font
					(size 1.016 1.016)
					(thickness 0.1524)
				)
			)
		)
		(duplicate_pad_numbers_are_jumpers no)
		(fp_poly
			(pts
				(arc
					(start 0.3556 0)
					(mid -0.3556 0)
					(end 0.3556 0)
				)
			)
			(stroke
				(width 0)
				(type default)
			)
			(fill no)
			(layer "F.CrtYd")
		)
		(fp_poly
			(pts
				(arc
					(start 0.6096 0)
					(mid -0.6096 0)
					(end 0.6096 0)
				)
			)
			(stroke
				(width 0)
				(type default)
			)
			(fill no)
			(layer "F.Fab")
		)
		(pad "1" smd circle
			(at 0 0)
			(size 0.7112 0.7112)
			(layers "F.Cu" "F.Mask" "F.Paste")
			(net "ZDEF_EXTA_TP_C1")
		)
	)
	(footprint ""
		(layer "F.Cu")
		(at 9.85012 -12.63904)
		(property "Reference" "R65"
			(at 0 0 0)
			(layer "F.SilkS")
			(hide yes)
			(effects
				(font
					(size 1.27 1.27)
				)
			)
		)
		(property "Value" "8K2R2J-3-GP"
			(at 0.064008 -3.993896 0)
			(unlocked yes)
			(layer "F.Fab")
			(hide yes)
			(effects
				(font
					(size 1.016 1.016)
					(thickness 0.1524)
				)
			)
		)
		(property "Device Type" "R402H16"
			(at 0.064008 -5.517896 0)
			(unlocked yes)
			(layer "F.Fab")
			(hide yes)
			(effects
				(font
					(size 1.016 1.016)
					(thickness 0.1524)
				)
			)
		)
		(duplicate_pad_numbers_are_jumpers no)
		(fp_line
			(start -0.508 -0.9398)
			(end -0.508 0.9398)
			(stroke
				(width 0.1524)
				(type default)
			)
			(layer "F.SilkS")
		)
		(fp_line
			(start 0.508 -0.9398)
			(end -0.508 -0.9398)
			(stroke
				(width 0.1524)
				(type default)
			)
			(layer "F.SilkS")
		)
		(fp_rect
			(start -0.508 0.9398)
			(end 0.508 -0.9398)
			(stroke
				(width 0)
				(type default)
			)
			(fill no)
			(layer "F.CrtYd")
		)
		(fp_rect
			(start -0.508 0.9398)
			(end 0.508 -0.9398)
			(stroke
				(width 0)
				(type default)
			)
			(fill no)
			(layer "F.Fab")
		)
		(pad "1" smd custom
			(at 0 -0.4445)
			(size 0.1397 0.1397)
			(layers "F.Cu" "F.Mask" "F.Paste")
			(net "P3V3_STBY")
			(options
				(clearance outline)
				(anchor circle)
			)
			(primitives
				(gr_poly
					(pts
						(arc
							(start -0.1778 -0.2794)
							(mid -0.249642 -0.249642)
							(end -0.2794 -0.1778)
						)
						(arc
							(start -0.2794 0.1778)
							(mid -0.249642 0.249642)
							(end -0.1778 0.2794)
						)
						(arc
							(start 0.1778 0.2794)
							(mid 0.249642 0.249642)
							(end 0.2794 0.1778)
						)
						(arc
							(start 0.2794 -0.1778)
							(mid 0.249642 -0.249642)
							(end 0.1778 -0.2794)
						)
					)
					(width 0)
					(fill yes)
				)
			)
		)
		(pad "2" smd custom
			(at 0 0.4445)
			(size 0.1397 0.1397)
			(layers "F.Cu" "F.Mask" "F.Paste")
			(net "SYS_RST_BTN_IN_N")
			(options
				(clearance outline)
				(anchor circle)
			)
			(primitives
				(gr_poly
					(pts
						(arc
							(start -0.1778 -0.2794)
							(mid -0.249642 -0.249642)
							(end -0.2794 -0.1778)
						)
						(arc
							(start -0.2794 0.1778)
							(mid -0.249642 0.249642)
							(end -0.1778 0.2794)
						)
						(arc
							(start 0.1778 0.2794)
							(mid 0.249642 0.249642)
							(end 0.2794 0.1778)
						)
						(arc
							(start 0.2794 -0.1778)
							(mid 0.249642 -0.249642)
							(end 0.1778 -0.2794)
						)
					)
					(width 0)
					(fill yes)
				)
			)
		)
	)
	(footprint ""
		(layer "F.Cu")
		(at 86.863428 -65.144396 -90)
		(property "Reference" "R8"
			(at 0 0 270)
			(layer "F.SilkS")
			(hide yes)
			(effects
				(font
					(size 1.27 1.27)
				)
			)
		)
		(property "Value" "0R2J-2-GP"
			(at 0.064008 -3.993896 270)
			(unlocked yes)
			(layer "F.Fab")
			(hide yes)
			(effects
				(font
					(size 1.016 1.016)
					(thickness 0.1524)
				)
			)
		)
		(property "Device Type" "R402H16"
			(at 0.064008 -5.517896 270)
			(unlocked yes)
			(layer "F.Fab")
			(hide yes)
			(effects
				(font
					(size 1.016 1.016)
					(thickness 0.1524)
				)
			)
		)
		(duplicate_pad_numbers_are_jumpers no)
		(fp_line
			(start -0.508 -0.9398)
			(end -0.508 0.9398)
			(stroke
				(width 0.1524)
				(type default)
			)
			(layer "F.SilkS")
		)
		(fp_line
			(start 0.508 -0.9398)
			(end -0.508 -0.9398)
			(stroke
				(width 0.1524)
				(type default)
			)
			(layer "F.SilkS")
		)
		(fp_rect
			(start -0.508 0.9398)
			(end 0.508 -0.9398)
			(stroke
				(width 0)
				(type default)
			)
			(fill no)
			(layer "F.CrtYd")
		)
		(fp_rect
			(start -0.508 0.9398)
			(end 0.508 -0.9398)
			(stroke
				(width 0)
				(type default)
			)
			(fill no)
			(layer "F.Fab")
		)
		(pad "1" smd custom
			(at 0 -0.4445 270)
			(size 0.1397 0.1397)
			(layers "F.Cu" "F.Mask" "F.Paste")
			(net "PCIE_COMP_TO_IOM_RST_4")
			(options
				(clearance outline)
				(anchor circle)
			)
			(primitives
				(gr_poly
					(pts
						(arc
							(start -0.1778 -0.2794)
							(mid -0.249642 -0.249642)
							(end -0.2794 -0.1778)
						)
						(arc
							(start -0.2794 0.1778)
							(mid -0.249642 0.249642)
							(end -0.1778 0.2794)
						)
						(arc
							(start 0.1778 0.2794)
							(mid 0.249642 0.249642)
							(end 0.2794 0.1778)
						)
						(arc
							(start 0.2794 -0.1778)
							(mid 0.249642 -0.249642)
							(end 0.1778 -0.2794)
						)
					)
					(width 0)
					(fill yes)
				)
			)
		)
		(pad "2" smd custom
			(at 0 0.4445 270)
			(size 0.1397 0.1397)
			(layers "F.Cu" "F.Mask" "F.Paste")
			(net "PCIE_COMP_TO_IOM_RST_4_R")
			(options
				(clearance outline)
				(anchor circle)
			)
			(primitives
				(gr_poly
					(pts
						(arc
							(start -0.1778 -0.2794)
							(mid -0.249642 -0.249642)
							(end -0.2794 -0.1778)
						)
						(arc
							(start -0.2794 0.1778)
							(mid -0.249642 0.249642)
							(end -0.1778 0.2794)
						)
						(arc
							(start 0.1778 0.2794)
							(mid 0.249642 0.249642)
							(end 0.2794 0.1778)
						)
						(arc
							(start 0.2794 -0.1778)
							(mid 0.249642 -0.249642)
							(end 0.1778 -0.2794)
						)
					)
					(width 0)
					(fill yes)
				)
			)
		)
	)
	(footprint ""
		(layer "F.Cu")
		(at 61.3664 -152.654 90)
		(property "Reference" "R340"
			(at 0 0 90)
			(layer "F.SilkS")
			(hide yes)
			(effects
				(font
					(size 1.27 1.27)
				)
			)
		)
		(property "Value" "8K2R2J-3-GP"
			(at 0.064008 -3.993896 90)
			(unlocked yes)
			(layer "F.Fab")
			(hide yes)
			(effects
				(font
					(size 1.016 1.016)
					(thickness 0.1524)
				)
			)
		)
		(property "Device Type" "R402H16"
			(at 0.064008 -5.517896 90)
			(unlocked yes)
			(layer "F.Fab")
			(hide yes)
			(effects
				(font
					(size 1.016 1.016)
					(thickness 0.1524)
				)
			)
		)
		(duplicate_pad_numbers_are_jumpers no)
		(fp_line
			(start 0.508 -0.9398)
			(end -0.508 -0.9398)
			(stroke
				(width 0.1524)
				(type default)
			)
			(layer "F.SilkS")
		)
		(fp_line
			(start -0.508 -0.9398)
			(end -0.508 0.9398)
			(stroke
				(width 0.1524)
				(type default)
			)
			(layer "F.SilkS")
		)
		(fp_rect
			(start -0.508 0.9398)
			(end 0.508 -0.9398)
			(stroke
				(width 0)
				(type default)
			)
			(fill no)
			(layer "F.CrtYd")
		)
		(fp_rect
			(start -0.508 0.9398)
			(end 0.508 -0.9398)
			(stroke
				(width 0)
				(type default)
			)
			(fill no)
			(layer "F.Fab")
		)
		(pad "1" smd custom
			(at 0 -0.4445 90)
			(size 0.1397 0.1397)
			(layers "F.Cu" "F.Mask" "F.Paste")
			(net "PD_USB2BVRES")
			(options
				(clearance outline)
				(anchor circle)
			)
			(primitives
				(gr_poly
					(pts
						(arc
							(start -0.1778 -0.2794)
							(mid -0.249642 -0.249642)
							(end -0.2794 -0.1778)
						)
						(arc
							(start -0.2794 0.1778)
							(mid -0.249642 0.249642)
							(end -0.1778 0.2794)
						)
						(arc
							(start 0.1778 0.2794)
							(mid 0.249642 0.249642)
							(end 0.2794 0.1778)
						)
						(arc
							(start 0.2794 -0.1778)
							(mid 0.249642 -0.249642)
							(end 0.1778 -0.2794)
						)
					)
					(width 0)
					(fill yes)
				)
			)
		)
		(pad "2" smd custom
			(at 0 0.4445 90)
			(size 0.1397 0.1397)
			(layers "F.Cu" "F.Mask" "F.Paste")
			(net "GND")
			(options
				(clearance outline)
				(anchor circle)
			)
			(primitives
				(gr_poly
					(pts
						(arc
							(start -0.1778 -0.2794)
							(mid -0.249642 -0.249642)
							(end -0.2794 -0.1778)
						)
						(arc
							(start -0.2794 0.1778)
							(mid -0.249642 0.249642)
							(end -0.1778 0.2794)
						)
						(arc
							(start 0.1778 0.2794)
							(mid 0.249642 0.249642)
							(end 0.2794 0.1778)
						)
						(arc
							(start 0.2794 -0.1778)
							(mid 0.249642 -0.249642)
							(end 0.1778 -0.2794)
						)
					)
					(width 0)
					(fill yes)
				)
			)
		)
	)
	(footprint ""
		(layer "F.Cu")
		(at 69.52488 -182.60568 90)
		(property "Reference" "R509"
			(at 0 0 90)
			(layer "F.SilkS")
			(hide yes)
			(effects
				(font
					(size 1.27 1.27)
				)
			)
		)
		(property "Value" "4K75R2F-1-GP"
			(at 0.064008 -3.993896 90)
			(unlocked yes)
			(layer "F.Fab")
			(hide yes)
			(effects
				(font
					(size 1.016 1.016)
					(thickness 0.1524)
				)
			)
		)
		(property "Device Type" "R402H16"
			(at 0.064008 -5.517896 90)
			(unlocked yes)
			(layer "F.Fab")
			(hide yes)
			(effects
				(font
					(size 1.016 1.016)
					(thickness 0.1524)
				)
			)
		)
		(duplicate_pad_numbers_are_jumpers no)
		(fp_line
			(start 0.508 -0.9398)
			(end -0.508 -0.9398)
			(stroke
				(width 0.1524)
				(type default)
			)
			(layer "F.SilkS")
		)
		(fp_line
			(start -0.508 -0.9398)
			(end -0.508 0.9398)
			(stroke
				(width 0.1524)
				(type default)
			)
			(layer "F.SilkS")
		)
		(fp_rect
			(start -0.508 0.9398)
			(end 0.508 -0.9398)
			(stroke
				(width 0)
				(type default)
			)
			(fill no)
			(layer "F.CrtYd")
		)
		(fp_rect
			(start -0.508 0.9398)
			(end 0.508 -0.9398)
			(stroke
				(width 0)
				(type default)
			)
			(fill no)
			(layer "F.Fab")
		)
		(pad "1" smd custom
			(at 0 -0.4445 90)
			(size 0.1397 0.1397)
			(layers "F.Cu" "F.Mask" "F.Paste")
			(net "P3V3_STBY")
			(options
				(clearance outline)
				(anchor circle)
			)
			(primitives
				(gr_poly
					(pts
						(arc
							(start -0.1778 -0.2794)
							(mid -0.249642 -0.249642)
							(end -0.2794 -0.1778)
						)
						(arc
							(start -0.2794 0.1778)
							(mid -0.249642 0.249642)
							(end -0.1778 0.2794)
						)
						(arc
							(start 0.1778 0.2794)
							(mid 0.249642 0.249642)
							(end 0.2794 0.1778)
						)
						(arc
							(start 0.2794 -0.1778)
							(mid 0.249642 -0.249642)
							(end 0.1778 -0.2794)
						)
					)
					(width 0)
					(fill yes)
				)
			)
		)
		(pad "2" smd custom
			(at 0 0.4445 90)
			(size 0.1397 0.1397)
			(layers "F.Cu" "F.Mask" "F.Paste")
			(net "TPS74801_P2V5_STBY_EN")
			(options
				(clearance outline)
				(anchor circle)
			)
			(primitives
				(gr_poly
					(pts
						(arc
							(start -0.1778 -0.2794)
							(mid -0.249642 -0.249642)
							(end -0.2794 -0.1778)
						)
						(arc
							(start -0.2794 0.1778)
							(mid -0.249642 0.249642)
							(end -0.1778 0.2794)
						)
						(arc
							(start 0.1778 0.2794)
							(mid 0.249642 0.249642)
							(end 0.2794 0.1778)
						)
						(arc
							(start 0.2794 -0.1778)
							(mid 0.249642 -0.249642)
							(end 0.1778 -0.2794)
						)
					)
					(width 0)
					(fill yes)
				)
			)
		)
	)
	(footprint ""
		(layer "F.Cu")
		(at 162.60064 -132.979922 180)
		(property "Reference" "R517"
			(at 0 0 180)
			(layer "F.SilkS")
			(hide yes)
			(effects
				(font
					(size 1.27 1.27)
				)
			)
		)
		(property "Value" "0R2J-2-GP"
			(at 0.064008 -3.993896 180)
			(unlocked yes)
			(layer "F.Fab")
			(hide yes)
			(effects
				(font
					(size 1.016 1.016)
					(thickness 0.1524)
				)
			)
		)
		(property "Device Type" "R402H16"
			(at 0.064008 -5.517896 180)
			(unlocked yes)
			(layer "F.Fab")
			(hide yes)
			(effects
				(font
					(size 1.016 1.016)
					(thickness 0.1524)
				)
			)
		)
		(duplicate_pad_numbers_are_jumpers no)
		(fp_line
			(start 0.508 -0.9398)
			(end -0.508 -0.9398)
			(stroke
				(width 0.1524)
				(type default)
			)
			(layer "F.SilkS")
		)
		(fp_line
			(start -0.508 -0.9398)
			(end -0.508 0.9398)
			(stroke
				(width 0.1524)
				(type default)
			)
			(layer "F.SilkS")
		)
		(fp_rect
			(start -0.508 0.9398)
			(end 0.508 -0.9398)
			(stroke
				(width 0)
				(type default)
			)
			(fill no)
			(layer "F.CrtYd")
		)
		(fp_rect
			(start -0.508 0.9398)
			(end 0.508 -0.9398)
			(stroke
				(width 0)
				(type default)
			)
			(fill no)
			(layer "F.Fab")
		)
		(pad "1" smd custom
			(at 0 -0.4445 180)
			(size 0.1397 0.1397)
			(layers "F.Cu" "F.Mask" "F.Paste")
			(net "P1V8_STBY_VBST_RR")
			(options
				(clearance outline)
				(anchor circle)
			)
			(primitives
				(gr_poly
					(pts
						(arc
							(start -0.1778 -0.2794)
							(mid -0.249642 -0.249642)
							(end -0.2794 -0.1778)
						)
						(arc
							(start -0.2794 0.1778)
							(mid -0.249642 0.249642)
							(end -0.1778 0.2794)
						)
						(arc
							(start 0.1778 0.2794)
							(mid 0.249642 0.249642)
							(end 0.2794 0.1778)
						)
						(arc
							(start 0.2794 -0.1778)
							(mid 0.249642 -0.249642)
							(end 0.1778 -0.2794)
						)
					)
					(width 0)
					(fill yes)
				)
			)
		)
		(pad "2" smd custom
			(at 0 0.4445 180)
			(size 0.1397 0.1397)
			(layers "F.Cu" "F.Mask" "F.Paste")
			(net "P1V8_STBY_VBST")
			(options
				(clearance outline)
				(anchor circle)
			)
			(primitives
				(gr_poly
					(pts
						(arc
							(start -0.1778 -0.2794)
							(mid -0.249642 -0.249642)
							(end -0.2794 -0.1778)
						)
						(arc
							(start -0.2794 0.1778)
							(mid -0.249642 0.249642)
							(end -0.1778 0.2794)
						)
						(arc
							(start 0.1778 0.2794)
							(mid 0.249642 0.249642)
							(end 0.2794 0.1778)
						)
						(arc
							(start 0.2794 -0.1778)
							(mid 0.249642 -0.249642)
							(end 0.1778 -0.2794)
						)
					)
					(width 0)
					(fill yes)
				)
			)
		)
	)
	(footprint ""
		(layer "F.Cu")
		(at 20.21078 -14.41704 180)
		(property "Reference" "R45"
			(at 0 0 180)
			(layer "F.SilkS")
			(hide yes)
			(effects
				(font
					(size 1.27 1.27)
				)
			)
		)
		(property "Value" "1MR2F-GP"
			(at 0.064008 -3.993896 180)
			(unlocked yes)
			(layer "F.Fab")
			(hide yes)
			(effects
				(font
					(size 1.016 1.016)
					(thickness 0.1524)
				)
			)
		)
		(property "Device Type" "R402H16"
			(at 0.064008 -5.517896 180)
			(unlocked yes)
			(layer "F.Fab")
			(hide yes)
			(effects
				(font
					(size 1.016 1.016)
					(thickness 0.1524)
				)
			)
		)
		(duplicate_pad_numbers_are_jumpers no)
		(fp_line
			(start 0.508 -0.9398)
			(end -0.508 -0.9398)
			(stroke
				(width 0.1524)
				(type default)
			)
			(layer "F.SilkS")
		)
		(fp_line
			(start -0.508 -0.9398)
			(end -0.508 0.9398)
			(stroke
				(width 0.1524)
				(type default)
			)
			(layer "F.SilkS")
		)
		(fp_rect
			(start -0.508 0.9398)
			(end 0.508 -0.9398)
			(stroke
				(width 0)
				(type default)
			)
			(fill no)
			(layer "F.CrtYd")
		)
		(fp_rect
			(start -0.508 0.9398)
			(end 0.508 -0.9398)
			(stroke
				(width 0)
				(type default)
			)
			(fill no)
			(layer "F.Fab")
		)
		(pad "1" smd custom
			(at 0 -0.4445 180)
			(size 0.1397 0.1397)
			(layers "F.Cu" "F.Mask" "F.Paste")
			(net "PWR_BTN_GND")
			(options
				(clearance outline)
				(anchor circle)
			)
			(primitives
				(gr_poly
					(pts
						(arc
							(start -0.1778 -0.2794)
							(mid -0.249642 -0.249642)
							(end -0.2794 -0.1778)
						)
						(arc
							(start -0.2794 0.1778)
							(mid -0.249642 0.249642)
							(end -0.1778 0.2794)
						)
						(arc
							(start 0.1778 0.2794)
							(mid 0.249642 0.249642)
							(end 0.2794 0.1778)
						)
						(arc
							(start 0.2794 -0.1778)
							(mid 0.249642 -0.249642)
							(end 0.1778 -0.2794)
						)
					)
					(width 0)
					(fill yes)
				)
			)
		)
		(pad "2" smd custom
			(at 0 0.4445 180)
			(size 0.1397 0.1397)
			(layers "F.Cu" "F.Mask" "F.Paste")
			(net "GND")
			(options
				(clearance outline)
				(anchor circle)
			)
			(primitives
				(gr_poly
					(pts
						(arc
							(start -0.1778 -0.2794)
							(mid -0.249642 -0.249642)
							(end -0.2794 -0.1778)
						)
						(arc
							(start -0.2794 0.1778)
							(mid -0.249642 0.249642)
							(end -0.1778 0.2794)
						)
						(arc
							(start 0.1778 0.2794)
							(mid 0.249642 0.249642)
							(end 0.2794 0.1778)
						)
						(arc
							(start 0.2794 -0.1778)
							(mid 0.249642 -0.249642)
							(end 0.1778 -0.2794)
						)
					)
					(width 0)
					(fill yes)
				)
			)
		)
	)
	(footprint ""
		(layer "F.Cu")
		(at 174.560738 -69.45122 90)
		(property "Reference" "R576"
			(at 0 0 90)
			(layer "F.SilkS")
			(hide yes)
			(effects
				(font
					(size 1.27 1.27)
				)
			)
		)
		(property "Value" "2K2R2F-GP"
			(at 0.064008 -3.993896 90)
			(unlocked yes)
			(layer "F.Fab")
			(hide yes)
			(effects
				(font
					(size 1.016 1.016)
					(thickness 0.1524)
				)
			)
		)
		(property "Device Type" "R402H16"
			(at 0.064008 -5.517896 90)
			(unlocked yes)
			(layer "F.Fab")
			(hide yes)
			(effects
				(font
					(size 1.016 1.016)
					(thickness 0.1524)
				)
			)
		)
		(duplicate_pad_numbers_are_jumpers no)
		(fp_line
			(start 0.508 -0.9398)
			(end -0.508 -0.9398)
			(stroke
				(width 0.1524)
				(type default)
			)
			(layer "F.SilkS")
		)
		(fp_line
			(start -0.508 -0.9398)
			(end -0.508 0.9398)
			(stroke
				(width 0.1524)
				(type default)
			)
			(layer "F.SilkS")
		)
		(fp_rect
			(start -0.508 0.9398)
			(end 0.508 -0.9398)
			(stroke
				(width 0)
				(type default)
			)
			(fill no)
			(layer "F.CrtYd")
		)
		(fp_rect
			(start -0.508 0.9398)
			(end 0.508 -0.9398)
			(stroke
				(width 0)
				(type default)
			)
			(fill no)
			(layer "F.Fab")
		)
		(pad "1" smd custom
			(at 0 -0.4445 90)
			(size 0.1397 0.1397)
			(layers "F.Cu" "F.Mask" "F.Paste")
			(net "P1V8")
			(options
				(clearance outline)
				(anchor circle)
			)
			(primitives
				(gr_poly
					(pts
						(arc
							(start -0.1778 -0.2794)
							(mid -0.249642 -0.249642)
							(end -0.2794 -0.1778)
						)
						(arc
							(start -0.2794 0.1778)
							(mid -0.249642 0.249642)
							(end -0.1778 0.2794)
						)
						(arc
							(start 0.1778 0.2794)
							(mid 0.249642 0.249642)
							(end 0.2794 0.1778)
						)
						(arc
							(start 0.2794 -0.1778)
							(mid 0.249642 -0.249642)
							(end 0.1778 -0.2794)
						)
					)
					(width 0)
					(fill yes)
				)
			)
		)
		(pad "2" smd custom
			(at 0 0.4445 90)
			(size 0.1397 0.1397)
			(layers "F.Cu" "F.Mask" "F.Paste")
			(net "IOC_SDA_1")
			(options
				(clearance outline)
				(anchor circle)
			)
			(primitives
				(gr_poly
					(pts
						(arc
							(start -0.1778 -0.2794)
							(mid -0.249642 -0.249642)
							(end -0.2794 -0.1778)
						)
						(arc
							(start -0.2794 0.1778)
							(mid -0.249642 0.249642)
							(end -0.1778 0.2794)
						)
						(arc
							(start 0.1778 0.2794)
							(mid 0.249642 0.249642)
							(end 0.2794 0.1778)
						)
						(arc
							(start 0.2794 -0.1778)
							(mid 0.249642 -0.249642)
							(end 0.1778 -0.2794)
						)
					)
					(width 0)
					(fill yes)
				)
			)
		)
	)
)
